(kicad_pcb
	(version 20241229)
	(generator "pcbnew")
	(generator_version "9.0")
	(general
		(thickness 1.61)
		(legacy_teardrops no)
	)
	(paper "A3")
	(title_block
		(title "SO-DIMM DDR5 Tester")
		(date "2025-11-26")
		(rev "1.3.0")
		(comment 9 "footprints 90-95 of 627")
	)
	(layers
		(0 "F.Cu" signal)
		(4 "In1.Cu" power)
		(6 "In2.Cu" mixed)
		(8 "In3.Cu" power)
		(10 "In4.Cu" mixed)
		(12 "In5.Cu" power)
		(14 "In6.Cu" mixed)
		(16 "In7.Cu" power)
		(18 "In8.Cu" power)
		(20 "In9.Cu" mixed)
		(22 "In10.Cu" power)
		(2 "B.Cu" signal)
		(9 "F.Adhes" user "F.Adhesive")
		(11 "B.Adhes" user "B.Adhesive")
		(13 "F.Paste" user)
		(15 "B.Paste" user)
		(5 "F.SilkS" user "F.Silkscreen")
		(7 "B.SilkS" user "B.Silkscreen")
		(1 "F.Mask" user)
		(3 "B.Mask" user)
		(17 "Dwgs.User" user "User.Drawings")
		(19 "Cmts.User" user "User.Comments")
		(21 "Eco1.User" user "User.Eco1")
		(23 "Eco2.User" user "User.Eco2")
		(25 "Edge.Cuts" user)
		(27 "Margin" user)
		(31 "F.CrtYd" user "F.Courtyard")
		(29 "B.CrtYd" user "B.Courtyard")
		(35 "F.Fab" user)
		(33 "B.Fab" user)
	)
	(footprint "antmicro-footprints:NetTie-2_SMD_Pad0.127mm"
		(layer "F.Cu")
		(at 187.85 171.701 180)
		(descr "Net tie, 2 pin, 0.127mm  SMD pads")
		(tags "net tie")
		(property "Reference" "NT13"
			(at -0.128 -1.345 180)
			(layer "F.SilkS")
			(hide yes)
			(effects
				(font
					(size 0.7 0.7)
					(thickness 0.15)
				)
				(justify left bottom)
			)
		)
		(property "Value" "Net-Tie_P0.127mm"
			(at 0 1.199 180)
			(layer "F.Fab")
			(effects
				(font
					(size 0.7 0.7)
					(thickness 0.15)
				)
				(justify left bottom)
			)
		)
		(property "Author" "Antmicro"
			(at 375.7 343.402 0)
			(layer "F.Fab")
			(hide yes)
			(effects
				(font
					(size 1 1)
					(thickness 0.15)
				)
			)
		)
		(property "License" "Apache-2.0"
			(at 375.7 343.402 0)
			(layer "F.Fab")
			(hide yes)
			(effects
				(font
					(size 1 1)
					(thickness 0.15)
				)
			)
		)
		(property "MPN" ""
			(at 375.7 343.402 0)
			(layer "F.Fab")
			(hide yes)
			(effects
				(font
					(size 1 1)
					(thickness 0.15)
				)
			)
		)
		(property "Manufacturer" ""
			(at 375.7 343.402 0)
			(layer "F.Fab")
			(hide yes)
			(effects
				(font
					(size 1 1)
					(thickness 0.15)
				)
			)
		)
		(property ki_fp_filters "Net*Tie*")
		(sheetname "/Supply/")
		(sheetfile "supply.kicad_sch")
		(attr smd exclude_from_pos_files exclude_from_bom)
		(net_tie_pad_groups "1, 2")
		(fp_poly
			(pts
				(xy -0.0635 -0.0635) (xy 0.0625 -0.0635) (xy 0.0625 0.0635) (xy -0.0635 0.0635)
			)
			(stroke
				(width 0)
				(type solid)
			)
			(fill yes)
			(layer "F.Cu")
		)
		(pad "1" smd roundrect
			(at -0.127 0)
			(size 0.127 0.127)
			(layers "F.Cu")
			(roundrect_rratio 0.5)
			(chamfer_ratio 0)
			(chamfer top_left bottom_left)
			(net 245 "/Supply/3V3_SEN_-")
			(pinfunction "1")
			(pintype "passive")
		)
		(pad "2" smd roundrect
			(at 0.126 0 180)
			(size 0.127 0.127)
			(layers "F.Cu")
			(roundrect_rratio 0.5)
			(chamfer_ratio 0)
			(chamfer top_left bottom_left)
			(net 200 "+3V3")
			(pinfunction "2")
			(pintype "passive")
		)
	)
	(footprint "antmicro-footprints:C_0805_2012Metric"
		(layer "F.Cu")
		(at 172.919503 197.376)
		(descr "Capacitor SMD 0805")
		(tags "capacitor SMD 0805")
		(property "Reference" "C202"
			(at -2.10551 -1.198678 0)
			(layer "F.SilkS")
			(hide yes)
			(effects
				(font
					(size 0.7 0.7)
					(thickness 0.15)
				)
				(justify left bottom)
			)
		)
		(property "Value" "C_22u_25V_0805"
			(at -2.055717 1.963152 0)
			(layer "F.Fab")
			(effects
				(font
					(size 0.7 0.7)
					(thickness 0.15)
				)
				(justify left bottom)
			)
		)
		(property "Datasheet" "https://product.samsungsem.com/mlcc/CL21A226MAYNNN.do"
			(at 0 0 0)
			(layer "F.Fab")
			(hide yes)
			(effects
				(font
					(size 1.27 1.27)
					(thickness 0.15)
				)
			)
		)
		(property "Author" "Antmicro"
			(at 0 0 0)
			(layer "F.Fab")
			(hide yes)
			(effects
				(font
					(size 1 1)
					(thickness 0.15)
				)
			)
		)
		(property "Dielectric" ""
			(at 0 0 0)
			(layer "F.Fab")
			(hide yes)
			(effects
				(font
					(size 1 1)
					(thickness 0.15)
				)
			)
		)
		(property "License" "Apache-2.0"
			(at 0 0 0)
			(layer "F.Fab")
			(hide yes)
			(effects
				(font
					(size 1 1)
					(thickness 0.15)
				)
			)
		)
		(property "MPN" "CL21A226MAYNNNE"
			(at 0 0 0)
			(layer "F.Fab")
			(hide yes)
			(effects
				(font
					(size 1 1)
					(thickness 0.15)
				)
			)
		)
		(property "Manufacturer" "Samsung Electro-Mechanics"
			(at 0 0 0)
			(layer "F.Fab")
			(hide yes)
			(effects
				(font
					(size 1 1)
					(thickness 0.15)
				)
			)
		)
		(property "Val" "22u_25V"
			(at 0 0 0)
			(layer "F.Fab")
			(hide yes)
			(effects
				(font
					(size 1 1)
					(thickness 0.15)
				)
			)
		)
		(property "Voltage" ""
			(at 0 0 0)
			(layer "F.Fab")
			(hide yes)
			(effects
				(font
					(size 1 1)
					(thickness 0.15)
				)
			)
		)
		(sheetname "/Supply/")
		(sheetfile "supply.kicad_sch")
		(attr smd)
		(fp_line
			(start -0.3 -0.8)
			(end 0.3 -0.8)
			(stroke
				(width 0.15)
				(type solid)
			)
			(layer "F.SilkS")
		)
		(fp_line
			(start -0.3 0.8)
			(end 0.3 0.8)
			(stroke
				(width 0.15)
				(type solid)
			)
			(layer "F.SilkS")
		)
		(fp_rect
			(start -1.9 -0.93)
			(end 1.9 0.93)
			(stroke
				(width 0.05)
				(type solid)
			)
			(fill no)
			(layer "F.CrtYd")
		)
		(fp_rect
			(start -0.95 -0.675)
			(end 0.95 0.675)
			(stroke
				(width 0.15)
				(type solid)
			)
			(fill no)
			(layer "F.Fab")
		)
		(pad "1" smd rect
			(at -1.05 0)
			(size 1.2 1.2)
			(layers "F.Cu" "F.Mask" "F.Paste")
			(net 1 "GND")
			(pintype "passive")
		)
		(pad "2" smd rect
			(at 1.05 0)
			(size 1.2 1.2)
			(layers "F.Cu" "F.Mask" "F.Paste")
			(net 38 "VDC")
			(pintype "passive")
		)
	)
	(footprint "antmicro-footprints:R_1206_3216Metric"
		(layer "F.Cu")
		(at 188.6555 162.001 180)
		(property "Reference" "R146"
			(at 0.5055 -1.949 180)
			(layer "F.SilkS")
			(effects
				(font
					(size 0.7 0.7)
					(thickness 0.15)
				)
				(justify left bottom)
			)
		)
		(property "Value" "R_0R01_1206"
			(at -2.422356 2.103591 180)
			(layer "F.Fab")
			(effects
				(font
					(size 0.7 0.7)
					(thickness 0.15)
				)
				(justify left bottom)
			)
		)
		(property "Datasheet" "https://www.yageo.com/upload/media/product/productsearch/datasheet/rchip/PYu-RL_Group_521_RoHS_L_2.pdf"
			(at 0 0 180)
			(layer "F.Fab")
			(hide yes)
			(effects
				(font
					(size 1.27 1.27)
					(thickness 0.15)
				)
			)
		)
		(property "Author" "Antmicro"
			(at 377.311 324.002 0)
			(layer "F.Fab")
			(hide yes)
			(effects
				(font
					(size 1 1)
					(thickness 0.15)
				)
			)
		)
		(property "License" "Apache-2.0"
			(at 377.311 324.002 0)
			(layer "F.Fab")
			(hide yes)
			(effects
				(font
					(size 1 1)
					(thickness 0.15)
				)
			)
		)
		(property "MPN" "RL1206FR-7W0R01L"
			(at 377.311 324.002 0)
			(layer "F.Fab")
			(hide yes)
			(effects
				(font
					(size 1 1)
					(thickness 0.15)
				)
			)
		)
		(property "Manufacturer" "YAGEO"
			(at 377.311 324.002 0)
			(layer "F.Fab")
			(hide yes)
			(effects
				(font
					(size 1 1)
					(thickness 0.15)
				)
			)
		)
		(property "Tolerance" "1%"
			(at 377.311 324.002 0)
			(layer "F.Fab")
			(hide yes)
			(effects
				(font
					(size 1 1)
					(thickness 0.15)
				)
			)
		)
		(property "Val" "0R01"
			(at 377.311 324.002 0)
			(layer "F.Fab")
			(hide yes)
			(effects
				(font
					(size 1 1)
					(thickness 0.15)
				)
			)
		)
		(sheetname "/Supply/")
		(sheetfile "supply.kicad_sch")
		(attr smd)
		(fp_line
			(start 0 0.9)
			(end 0.498 0.9)
			(stroke
				(width 0.15)
				(type solid)
			)
			(layer "F.SilkS")
		)
		(fp_line
			(start 0 0.9)
			(end -0.5 0.9)
			(stroke
				(width 0.15)
				(type solid)
			)
			(layer "F.SilkS")
		)
		(fp_line
			(start 0 -0.902)
			(end 0.498 -0.902)
			(stroke
				(width 0.15)
				(type solid)
			)
			(layer "F.SilkS")
		)
		(fp_line
			(start 0 -0.902)
			(end -0.5 -0.902)
			(stroke
				(width 0.15)
				(type solid)
			)
			(layer "F.SilkS")
		)
		(fp_rect
			(start -2.25 -1.05)
			(end 2.25 1.05)
			(stroke
				(width 0.05)
				(type solid)
			)
			(fill no)
			(layer "F.CrtYd")
		)
		(fp_line
			(start 1.6 -0.802)
			(end 1.6 0.8)
			(stroke
				(width 0.15)
				(type solid)
			)
			(layer "F.Fab")
		)
		(fp_line
			(start -1.601 0.8)
			(end 1.6 0.8)
			(stroke
				(width 0.15)
				(type solid)
			)
			(layer "F.Fab")
		)
		(fp_line
			(start -1.601 -0.802)
			(end 1.6 -0.802)
			(stroke
				(width 0.15)
				(type solid)
			)
			(layer "F.Fab")
		)
		(fp_line
			(start -1.601 -0.802)
			(end -1.601 0.8)
			(stroke
				(width 0.15)
				(type solid)
			)
			(layer "F.Fab")
		)
		(pad "1" smd roundrect
			(at -1.5 0 180)
			(size 1.2 1.8)
			(layers "F.Cu" "F.Mask" "F.Paste")
			(roundrect_rratio 0.15)
			(net 60 "/Supply/5V_local")
			(pintype "passive")
		)
		(pad "2" smd roundrect
			(at 1.499 0 180)
			(size 1.2 1.8)
			(layers "F.Cu" "F.Mask" "F.Paste")
			(roundrect_rratio 0.15)
			(net 201 "+5V")
			(pintype "passive")
		)
	)
	(footprint "antmicro-footprints:NetTie-2_SMD_Pad0.127mm"
		(layer "F.Cu")
		(at 189.5 179.5)
		(descr "Net tie, 2 pin, 0.127mm  SMD pads")
		(tags "net tie")
		(property "Reference" "NT2"
			(at -0.128 -1.345 0)
			(layer "F.SilkS")
			(hide yes)
			(effects
				(font
					(size 0.7 0.7)
					(thickness 0.15)
				)
				(justify left bottom)
			)
		)
		(property "Value" "Net-Tie_P0.127mm"
			(at 0 1.199 0)
			(layer "F.Fab")
			(effects
				(font
					(size 0.7 0.7)
					(thickness 0.15)
				)
				(justify left bottom)
			)
		)
		(property "Author" "Antmicro"
			(at 0 0 0)
			(layer "F.Fab")
			(hide yes)
			(effects
				(font
					(size 1 1)
					(thickness 0.15)
				)
			)
		)
		(property "License" "Apache-2.0"
			(at 0 0 0)
			(layer "F.Fab")
			(hide yes)
			(effects
				(font
					(size 1 1)
					(thickness 0.15)
				)
			)
		)
		(property "MPN" ""
			(at 0 0 0)
			(layer "F.Fab")
			(hide yes)
			(effects
				(font
					(size 1 1)
					(thickness 0.15)
				)
			)
		)
		(property "Manufacturer" ""
			(at 0 0 0)
			(layer "F.Fab")
			(hide yes)
			(effects
				(font
					(size 1 1)
					(thickness 0.15)
				)
			)
		)
		(property ki_fp_filters "Net*Tie*")
		(sheetname "/Supply/")
		(sheetfile "supply.kicad_sch")
		(attr smd exclude_from_pos_files exclude_from_bom)
		(net_tie_pad_groups "1, 2")
		(fp_poly
			(pts
				(xy -0.0635 -0.0635) (xy 0.0625 -0.0635) (xy 0.0625 0.0635) (xy -0.0635 0.0635)
			)
			(stroke
				(width 0)
				(type solid)
			)
			(fill yes)
			(layer "F.Cu")
		)
		(pad "1" smd roundrect
			(at -0.127 0 180)
			(size 0.127 0.127)
			(layers "F.Cu")
			(roundrect_rratio 0.5)
			(chamfer_ratio 0)
			(chamfer top_left bottom_left)
			(net 244 "/Supply/1V8_SEN_+")
			(pinfunction "1")
			(pintype "passive")
		)
		(pad "2" smd roundrect
			(at 0.126 0)
			(size 0.127 0.127)
			(layers "F.Cu")
			(roundrect_rratio 0.5)
			(chamfer_ratio 0)
			(chamfer top_left bottom_left)
			(net 51 "/Supply/1V8_local")
			(pinfunction "2")
			(pintype "passive")
		)
	)
	(footprint "antmicro-footprints:C_0603_1608Metric"
		(layer "F.Cu")
		(at 199.981001 172.122)
		(descr "Capacitor SMD 0603")
		(tags "capacitor 0603")
		(property "Reference" "C193"
			(at -1.42757 -1.000252 0)
			(layer "F.SilkS")
			(hide yes)
			(effects
				(font
					(size 0.7 0.7)
					(thickness 0.15)
				)
				(justify left bottom)
			)
		)
		(property "Value" "C_22u_0603"
			(at -1.42757 1.770288 0)
			(layer "F.Fab")
			(effects
				(font
					(size 0.7 0.7)
					(thickness 0.15)
				)
				(justify left bottom)
			)
		)
		(property "Datasheet" "https://www.murata.com/products/productdetail?partno=GRM188R60J226MEA0%23"
			(at 0 0 0)
			(layer "F.Fab")
			(hide yes)
			(effects
				(font
					(size 1.27 1.27)
					(thickness 0.15)
				)
			)
		)
		(property "Author" "Antmicro"
			(at 0 0 0)
			(layer "F.Fab")
			(hide yes)
			(effects
				(font
					(size 1 1)
					(thickness 0.15)
				)
			)
		)
		(property "Dielectric" ""
			(at 0 0 0)
			(layer "F.Fab")
			(hide yes)
			(effects
				(font
					(size 1 1)
					(thickness 0.15)
				)
			)
		)
		(property "License" "Apache-2.0"
			(at 0 0 0)
			(layer "F.Fab")
			(hide yes)
			(effects
				(font
					(size 1 1)
					(thickness 0.15)
				)
			)
		)
		(property "MPN" "GRM188R60J226MEA0D"
			(at 0 0 0)
			(layer "F.Fab")
			(hide yes)
			(effects
				(font
					(size 1 1)
					(thickness 0.15)
				)
			)
		)
		(property "Manufacturer" "Murata"
			(at 0 0 0)
			(layer "F.Fab")
			(hide yes)
			(effects
				(font
					(size 1 1)
					(thickness 0.15)
				)
			)
		)
		(property "Val" "22u"
			(at 0 0 0)
			(layer "F.Fab")
			(hide yes)
			(effects
				(font
					(size 1 1)
					(thickness 0.15)
				)
			)
		)
		(property "Voltage" ""
			(at 0 0 0)
			(layer "F.Fab")
			(hide yes)
			(effects
				(font
					(size 1 1)
					(thickness 0.15)
				)
			)
		)
		(sheetname "/Supply/")
		(sheetfile "supply.kicad_sch")
		(fp_line
			(start -0.3 -0.3)
			(end 0.3 -0.3)
			(stroke
				(width 0.15)
				(type solid)
			)
			(layer "F.SilkS")
		)
		(fp_line
			(start -0.3 0.3)
			(end 0.3 0.3)
			(stroke
				(width 0.15)
				(type solid)
			)
			(layer "F.SilkS")
		)
		(fp_rect
			(start -1.24 -0.7)
			(end 1.24 0.7)
			(stroke
				(width 0.05)
				(type solid)
			)
			(fill no)
			(layer "F.CrtYd")
		)
		(fp_rect
			(start -0.8 -0.4)
			(end 0.8 0.4)
			(stroke
				(width 0.15)
				(type solid)
			)
			(fill no)
			(layer "F.Fab")
		)
		(pad "1" smd roundrect
			(at -0.7 0)
			(size 0.6 0.8)
			(layers "F.Cu" "F.Mask" "F.Paste")
			(roundrect_rratio 0.2)
			(net 1 "GND")
			(pintype "passive")
		)
		(pad "2" smd roundrect
			(at 0.7 0)
			(size 0.6 0.8)
			(layers "F.Cu" "F.Mask" "F.Paste")
			(roundrect_rratio 0.2)
			(net 56 "/Supply/1V2_local")
			(pintype "passive")
		)
	)
	(footprint "antmicro-footprints:C_0603_1608Metric"
		(layer "F.Cu")
		(at 191.168501 168.072 -90)
		(descr "Capacitor SMD 0603")
		(tags "capacitor 0603")
		(property "Reference" "C184"
			(at -1.42757 -1.000252 270)
			(layer "F.SilkS")
			(hide yes)
			(effects
				(font
					(size 0.7 0.7)
					(thickness 0.15)
				)
				(justify left bottom)
			)
		)
		(property "Value" "C_22u_0603"
			(at -1.42757 1.770288 270)
			(layer "F.Fab")
			(effects
				(font
					(size 0.7 0.7)
					(thickness 0.15)
				)
				(justify left bottom)
			)
		)
		(property "Datasheet" "https://www.murata.com/products/productdetail?partno=GRM188R60J226MEA0%23"
			(at 0 0 270)
			(layer "F.Fab")
			(hide yes)
			(effects
				(font
					(size 1.27 1.27)
					(thickness 0.15)
				)
			)
		)
		(property "Author" "Antmicro"
			(at 23.096501 359.240501 0)
			(layer "F.Fab")
			(hide yes)
			(effects
				(font
					(size 1 1)
					(thickness 0.15)
				)
			)
		)
		(property "Dielectric" ""
			(at 23.096501 359.240501 0)
			(layer "F.Fab")
			(hide yes)
			(effects
				(font
					(size 1 1)
					(thickness 0.15)
				)
			)
		)
		(property "License" "Apache-2.0"
			(at 23.096501 359.240501 0)
			(layer "F.Fab")
			(hide yes)
			(effects
				(font
					(size 1 1)
					(thickness 0.15)
				)
			)
		)
		(property "MPN" "GRM188R60J226MEA0D"
			(at 23.096501 359.240501 0)
			(layer "F.Fab")
			(hide yes)
			(effects
				(font
					(size 1 1)
					(thickness 0.15)
				)
			)
		)
		(property "Manufacturer" "Murata"
			(at 23.096501 359.240501 0)
			(layer "F.Fab")
			(hide yes)
			(effects
				(font
					(size 1 1)
					(thickness 0.15)
				)
			)
		)
		(property "Val" "22u"
			(at 23.096501 359.240501 0)
			(layer "F.Fab")
			(hide yes)
			(effects
				(font
					(size 1 1)
					(thickness 0.15)
				)
			)
		)
		(property "Voltage" ""
			(at 23.096501 359.240501 0)
			(layer "F.Fab")
			(hide yes)
			(effects
				(font
					(size 1 1)
					(thickness 0.15)
				)
			)
		)
		(sheetname "/Supply/")
		(sheetfile "supply.kicad_sch")
		(attr smd)
		(fp_line
			(start -0.3 0.3)
			(end 0.3 0.3)
			(stroke
				(width 0.15)
				(type solid)
			)
			(layer "F.SilkS")
		)
		(fp_line
			(start -0.3 -0.3)
			(end 0.3 -0.3)
			(stroke
				(width 0.15)
				(type solid)
			)
			(layer "F.SilkS")
		)
		(fp_rect
			(start -1.24 -0.7)
			(end 1.24 0.7)
			(stroke
				(width 0.05)
				(type solid)
			)
			(fill no)
			(layer "F.CrtYd")
		)
		(fp_rect
			(start -0.8 -0.4)
			(end 0.8 0.4)
			(stroke
				(width 0.15)
				(type solid)
			)
			(fill no)
			(layer "F.Fab")
		)
		(pad "1" smd roundrect
			(at -0.7 0 270)
			(size 0.6 0.8)
			(layers "F.Cu" "F.Mask" "F.Paste")
			(roundrect_rratio 0.2)
			(net 1 "GND")
			(pintype "passive")
		)
		(pad "2" smd roundrect
			(at 0.7 0 270)
			(size 0.6 0.8)
			(layers "F.Cu" "F.Mask" "F.Paste")
			(roundrect_rratio 0.2)
			(net 52 "/Supply/3V3_local")
			(pintype "passive")
		)
	)
)
